(kicad_pcb
	(version 20260206)
	(generator "pcbnew")
	(generator_version "10.0")
	(general
		(thickness 1.6)
		(legacy_teardrops no)
	)
	(paper "A4")
	(title_block
		(title "03242023_DA0F0TMBIJ0_F0T_Motherboard_J_brd_V01_OCP.brd")
		(comment 1 "Grand Teton / footprints 5693-5699 of 6105")
	)
	(layers
		(0 "F.Cu" signal "TOP")
		(4 "In1.Cu" signal "GND")
		(6 "In2.Cu" signal "IN1")
		(8 "In3.Cu" signal "GND1")
		(10 "In4.Cu" signal "IN2")
		(12 "In5.Cu" signal "GND2")
		(14 "In6.Cu" signal "IN3")
		(16 "In7.Cu" signal "GND3")
		(18 "In8.Cu" signal "VCC")
		(20 "In9.Cu" signal "VCC1")
		(22 "In10.Cu" signal "GND4")
		(24 "In11.Cu" signal "IN4")
		(26 "In12.Cu" signal "GND5")
		(28 "In13.Cu" signal "IN5")
		(30 "In14.Cu" signal "GND6")
		(32 "In15.Cu" signal "IN6")
		(34 "In16.Cu" signal "GND7")
		(2 "B.Cu" signal "BOTTOM")
		(9 "F.Adhes" user "F.Adhesive")
		(11 "B.Adhes" user "B.Adhesive")
		(13 "F.Paste" user "Package Geometry/Pastemask Top")
		(15 "B.Paste" user "Package Geometry/Pastemask Bottom")
		(5 "F.SilkS" user "Ref Des/Silkscreen Top")
		(7 "B.SilkS" user "Ref Des/Silkscreen Bottom")
		(1 "F.Mask" user "Board Geometry/Soldermask Top")
		(3 "B.Mask" user "Board Geometry/Soldermask Bottom")
		(17 "Dwgs.User" user "User.Drawings")
		(19 "Cmts.User" user "User.Comments")
		(21 "Eco1.User" user "User.Eco1")
		(23 "Eco2.User" user "User.Eco2")
		(25 "Edge.Cuts" user "Board Geometry/Outline")
		(27 "Margin" user)
		(31 "F.CrtYd" user "Package Geometry/Place Bound Top")
		(29 "B.CrtYd" user "Package Geometry/Place Bound Bottom")
		(35 "F.Fab" user "Ref Des/Assembly Top")
		(33 "B.Fab" user "Ref Des/Assembly Bottom")
	)
	(footprint ""
		(layer "B.Cu")
		(at 444.485014 -321.549776 -90)
		(property "Reference" "C40"
			(at 0 0 90)
			(layer "B.SilkS")
			(hide yes)
			(effects
				(font
					(size 1.27 1.27)
				)
				(justify mirror)
			)
		)
		(property "Value" ""
			(at 0 0 90)
			(layer "B.Fab")
			(effects
				(font
					(size 1.27 1.27)
				)
				(justify mirror)
			)
		)
		(duplicate_pad_numbers_are_jumpers no)
		(fp_line
			(start -1.524 0.762)
			(end 1.524 0.762)
			(stroke
				(width 0.1524)
				(type default)
			)
			(layer "B.SilkS")
		)
		(fp_line
			(start 1.524 0.762)
			(end 1.524 -0.762)
			(stroke
				(width 0.1524)
				(type default)
			)
			(layer "B.SilkS")
		)
		(fp_line
			(start -1.524 -0.762)
			(end -1.524 0.762)
			(stroke
				(width 0.1524)
				(type default)
			)
			(layer "B.SilkS")
		)
		(fp_line
			(start 1.524 -0.762)
			(end -1.524 -0.762)
			(stroke
				(width 0.1524)
				(type default)
			)
			(layer "B.SilkS")
		)
		(fp_line
			(start -1.1049 0.724916)
			(end -1.1049 -0.724916)
			(stroke
				(width 0.1)
				(type default)
			)
			(layer "B.Fab")
		)
		(fp_line
			(start 1.1049 0.724916)
			(end -1.1049 0.724916)
			(stroke
				(width 0.1)
				(type default)
			)
			(layer "B.Fab")
		)
		(fp_line
			(start -1.1049 -0.724916)
			(end 1.1049 -0.724916)
			(stroke
				(width 0.1)
				(type default)
			)
			(layer "B.Fab")
		)
		(fp_line
			(start 1.1049 -0.724916)
			(end 1.1049 0.724916)
			(stroke
				(width 0.1)
				(type default)
			)
			(layer "B.Fab")
		)
		(pad "1" smd rect
			(at 0.889 0 270)
			(size 1.016 1.27)
			(layers "B.Cu" "B.Mask" "B.Paste")
			(net "P12V_S3_AUX_CPU0_NVDIMM")
		)
		(pad "2" smd rect
			(at -0.889 0 270)
			(size 1.016 1.27)
			(layers "B.Cu" "B.Mask" "B.Paste")
			(net "GND")
		)
	)
	(footprint ""
		(layer "B.Cu")
		(at 343.840308 -62.056264 90)
		(property "Reference" "C162"
			(at 0 0 90)
			(layer "B.SilkS")
			(hide yes)
			(effects
				(font
					(size 1.27 1.27)
				)
				(justify mirror)
			)
		)
		(property "Value" ""
			(at 0 0 90)
			(layer "B.Fab")
			(effects
				(font
					(size 1.27 1.27)
				)
				(justify mirror)
			)
		)
		(duplicate_pad_numbers_are_jumpers no)
		(fp_line
			(start 0.299974 -0.150114)
			(end -0.299974 -0.150114)
			(stroke
				(width 0.1)
				(type default)
			)
			(layer "B.Fab")
		)
		(fp_line
			(start -0.299974 -0.150114)
			(end -0.299974 0.150114)
			(stroke
				(width 0.1)
				(type default)
			)
			(layer "B.Fab")
		)
		(fp_line
			(start 0.299974 0.150114)
			(end 0.299974 -0.150114)
			(stroke
				(width 0.1)
				(type default)
			)
			(layer "B.Fab")
		)
		(fp_line
			(start -0.299974 0.150114)
			(end 0.299974 0.150114)
			(stroke
				(width 0.1)
				(type default)
			)
			(layer "B.Fab")
		)
		(pad "1" smd rect
			(at 0.2667 0 270)
			(size 0.3048 0.381)
			(layers "B.Cu" "B.Mask" "B.Paste")
			(net "DMI_CPU0_PCH_RX_C_DP<4>")
		)
		(pad "2" smd rect
			(at -0.2667 0 270)
			(size 0.3048 0.381)
			(layers "B.Cu" "B.Mask" "B.Paste")
			(net "DMI_CPU0_PCH_RX_DP<4>")
		)
	)
	(footprint ""
		(layer "B.Cu")
		(at 325.66483 -66.840354 -90)
		(property "Reference" "C1191"
			(at 0 0 90)
			(layer "B.SilkS")
			(hide yes)
			(effects
				(font
					(size 1.27 1.27)
				)
				(justify mirror)
			)
		)
		(property "Value" ""
			(at 0 0 90)
			(layer "B.Fab")
			(effects
				(font
					(size 1.27 1.27)
				)
				(justify mirror)
			)
		)
		(duplicate_pad_numbers_are_jumpers no)
		(fp_line
			(start -1.2954 0.5842)
			(end 1.2954 0.5842)
			(stroke
				(width 0.1524)
				(type default)
			)
			(layer "B.SilkS")
		)
		(fp_line
			(start 1.2954 0.5842)
			(end 1.2954 -0.5842)
			(stroke
				(width 0.1524)
				(type default)
			)
			(layer "B.SilkS")
		)
		(fp_line
			(start -1.2954 -0.5842)
			(end -1.2954 0.5842)
			(stroke
				(width 0.1524)
				(type default)
			)
			(layer "B.SilkS")
		)
		(fp_line
			(start 0 -0.5842)
			(end 0 0.5842)
			(stroke
				(width 0.1524)
				(type default)
			)
			(layer "B.SilkS")
		)
		(fp_line
			(start 1.2954 -0.5842)
			(end -1.2954 -0.5842)
			(stroke
				(width 0.1524)
				(type default)
			)
			(layer "B.SilkS")
		)
		(fp_line
			(start -0.8636 0.4572)
			(end 0.8636 0.4572)
			(stroke
				(width 0.1)
				(type default)
			)
			(layer "B.Fab")
		)
		(fp_line
			(start 0.8636 0.4572)
			(end 0.8636 0.4064)
			(stroke
				(width 0.1)
				(type default)
			)
			(layer "B.Fab")
		)
		(fp_line
			(start -1.1938 0.4064)
			(end -0.8636 0.4064)
			(stroke
				(width 0.1)
				(type default)
			)
			(layer "B.Fab")
		)
		(fp_line
			(start -0.8636 0.4064)
			(end -0.8636 0.4572)
			(stroke
				(width 0.1)
				(type default)
			)
			(layer "B.Fab")
		)
		(fp_line
			(start 0.8636 0.4064)
			(end 1.1938 0.4064)
			(stroke
				(width 0.1)
				(type default)
			)
			(layer "B.Fab")
		)
		(fp_line
			(start 1.1938 0.4064)
			(end 1.1938 -0.4064)
			(stroke
				(width 0.1)
				(type default)
			)
			(layer "B.Fab")
		)
		(fp_line
			(start -1.1938 -0.4064)
			(end -1.1938 0.4064)
			(stroke
				(width 0.1)
				(type default)
			)
			(layer "B.Fab")
		)
		(fp_line
			(start -0.8636 -0.4064)
			(end -1.1938 -0.4064)
			(stroke
				(width 0.1)
				(type default)
			)
			(layer "B.Fab")
		)
		(fp_line
			(start 0.8636 -0.4064)
			(end 0.8636 -0.4572)
			(stroke
				(width 0.1)
				(type default)
			)
			(layer "B.Fab")
		)
		(fp_line
			(start 1.1938 -0.4064)
			(end 0.8636 -0.4064)
			(stroke
				(width 0.1)
				(type default)
			)
			(layer "B.Fab")
		)
		(fp_line
			(start -0.8636 -0.4572)
			(end -0.8636 -0.4064)
			(stroke
				(width 0.1)
				(type default)
			)
			(layer "B.Fab")
		)
		(fp_line
			(start 0.8636 -0.4572)
			(end -0.8636 -0.4572)
			(stroke
				(width 0.1)
				(type default)
			)
			(layer "B.Fab")
		)
		(pad "1" smd rect
			(at 0.7366 0 180)
			(size 0.7112 0.8128)
			(layers "B.Cu" "B.Mask" "B.Paste")
			(net "P3V3_AUX")
		)
		(pad "2" smd rect
			(at -0.7366 0 180)
			(size 0.7112 0.8128)
			(layers "B.Cu" "B.Mask" "B.Paste")
			(net "GND")
		)
	)
	(footprint ""
		(layer "B.Cu")
		(at 185.503312 -319.023492 90)
		(property "Reference" "R903"
			(at 0 0 90)
			(layer "B.SilkS")
			(hide yes)
			(effects
				(font
					(size 1.27 1.27)
				)
				(justify mirror)
			)
		)
		(property "Value" ""
			(at 0 0 90)
			(layer "B.Fab")
			(effects
				(font
					(size 1.27 1.27)
				)
				(justify mirror)
			)
		)
		(duplicate_pad_numbers_are_jumpers no)
		(fp_line
			(start 0.7874 -0.4064)
			(end -0.7874 -0.4064)
			(stroke
				(width 0.1524)
				(type default)
			)
			(layer "B.SilkS")
		)
		(fp_line
			(start -0.7874 -0.4064)
			(end -0.7874 0.4064)
			(stroke
				(width 0.1524)
				(type default)
			)
			(layer "B.SilkS")
		)
		(fp_line
			(start 0.7874 0.4064)
			(end 0.7874 -0.4064)
			(stroke
				(width 0.1524)
				(type default)
			)
			(layer "B.SilkS")
		)
		(fp_line
			(start -0.7874 0.4064)
			(end 0.7874 0.4064)
			(stroke
				(width 0.1524)
				(type default)
			)
			(layer "B.SilkS")
		)
		(fp_line
			(start 0.67945 -0.305054)
			(end 0.12065 -0.305054)
			(stroke
				(width 0.1)
				(type default)
			)
			(layer "B.Fab")
		)
		(fp_line
			(start 0.12065 -0.305054)
			(end 0.12065 -0.2794)
			(stroke
				(width 0.1)
				(type default)
			)
			(layer "B.Fab")
		)
		(fp_line
			(start -0.12065 -0.3048)
			(end -0.67945 -0.3048)
			(stroke
				(width 0.1)
				(type default)
			)
			(layer "B.Fab")
		)
		(fp_line
			(start -0.67945 -0.3048)
			(end -0.67945 0.3048)
			(stroke
				(width 0.1)
				(type default)
			)
			(layer "B.Fab")
		)
		(fp_line
			(start 0.12065 -0.2794)
			(end -0.12065 -0.2794)
			(stroke
				(width 0.1)
				(type default)
			)
			(layer "B.Fab")
		)
		(fp_line
			(start -0.12065 -0.2794)
			(end -0.12065 -0.3048)
			(stroke
				(width 0.1)
				(type default)
			)
			(layer "B.Fab")
		)
		(fp_line
			(start 0.12065 0.2794)
			(end 0.12065 0.3048)
			(stroke
				(width 0.1)
				(type default)
			)
			(layer "B.Fab")
		)
		(fp_line
			(start -0.120396 0.2794)
			(end 0.12065 0.2794)
			(stroke
				(width 0.1)
				(type default)
			)
			(layer "B.Fab")
		)
		(fp_line
			(start 0.67945 0.3048)
			(end 0.67945 -0.305054)
			(stroke
				(width 0.1)
				(type default)
			)
			(layer "B.Fab")
		)
		(fp_line
			(start 0.12065 0.3048)
			(end 0.67945 0.3048)
			(stroke
				(width 0.1)
				(type default)
			)
			(layer "B.Fab")
		)
		(fp_line
			(start -0.120396 0.3048)
			(end -0.120396 0.2794)
			(stroke
				(width 0.1)
				(type default)
			)
			(layer "B.Fab")
		)
		(fp_line
			(start -0.67945 0.3048)
			(end -0.120396 0.3048)
			(stroke
				(width 0.1)
				(type default)
			)
			(layer "B.Fab")
		)
		(pad "1" smd circle
			(at 0.40005 0 270)
			(size 0 0)
			(layers "B.Cu" "B.Mask" "B.Paste")
			(net "PWRGD_CHF_CPU1_DIMM1")
		)
		(pad "2" smd circle
			(at -0.40005 0 270)
			(size 0 0)
			(layers "B.Cu" "B.Mask" "B.Paste")
			(net "PWRGD_FAIL_CPU1_EF")
		)
	)
	(footprint ""
		(layer "B.Cu")
		(at 430.362106 -125.165612 90)
		(property "Reference" "PR4236"
			(at 0 0 90)
			(layer "B.SilkS")
			(hide yes)
			(effects
				(font
					(size 1.27 1.27)
				)
				(justify mirror)
			)
		)
		(property "Value" ""
			(at 0 0 90)
			(layer "B.Fab")
			(effects
				(font
					(size 1.27 1.27)
				)
				(justify mirror)
			)
		)
		(duplicate_pad_numbers_are_jumpers no)
		(fp_line
			(start 0.7874 -0.4064)
			(end -0.7874 -0.4064)
			(stroke
				(width 0.1524)
				(type default)
			)
			(layer "B.SilkS")
		)
		(fp_line
			(start -0.7874 -0.4064)
			(end -0.7874 0.4064)
			(stroke
				(width 0.1524)
				(type default)
			)
			(layer "B.SilkS")
		)
		(fp_line
			(start 0.7874 0.4064)
			(end 0.7874 -0.4064)
			(stroke
				(width 0.1524)
				(type default)
			)
			(layer "B.SilkS")
		)
		(fp_line
			(start -0.7874 0.4064)
			(end 0.7874 0.4064)
			(stroke
				(width 0.1524)
				(type default)
			)
			(layer "B.SilkS")
		)
		(fp_line
			(start 0.67945 -0.305054)
			(end 0.12065 -0.305054)
			(stroke
				(width 0.1)
				(type default)
			)
			(layer "B.Fab")
		)
		(fp_line
			(start 0.12065 -0.305054)
			(end 0.12065 -0.2794)
			(stroke
				(width 0.1)
				(type default)
			)
			(layer "B.Fab")
		)
		(fp_line
			(start -0.12065 -0.3048)
			(end -0.67945 -0.3048)
			(stroke
				(width 0.1)
				(type default)
			)
			(layer "B.Fab")
		)
		(fp_line
			(start -0.67945 -0.3048)
			(end -0.67945 0.3048)
			(stroke
				(width 0.1)
				(type default)
			)
			(layer "B.Fab")
		)
		(fp_line
			(start 0.12065 -0.2794)
			(end -0.12065 -0.2794)
			(stroke
				(width 0.1)
				(type default)
			)
			(layer "B.Fab")
		)
		(fp_line
			(start -0.12065 -0.2794)
			(end -0.12065 -0.3048)
			(stroke
				(width 0.1)
				(type default)
			)
			(layer "B.Fab")
		)
		(fp_line
			(start 0.12065 0.2794)
			(end 0.12065 0.3048)
			(stroke
				(width 0.1)
				(type default)
			)
			(layer "B.Fab")
		)
		(fp_line
			(start -0.120396 0.2794)
			(end 0.12065 0.2794)
			(stroke
				(width 0.1)
				(type default)
			)
			(layer "B.Fab")
		)
		(fp_line
			(start 0.67945 0.3048)
			(end 0.67945 -0.305054)
			(stroke
				(width 0.1)
				(type default)
			)
			(layer "B.Fab")
		)
		(fp_line
			(start 0.12065 0.3048)
			(end 0.67945 0.3048)
			(stroke
				(width 0.1)
				(type default)
			)
			(layer "B.Fab")
		)
		(fp_line
			(start -0.120396 0.3048)
			(end -0.120396 0.2794)
			(stroke
				(width 0.1)
				(type default)
			)
			(layer "B.Fab")
		)
		(fp_line
			(start -0.67945 0.3048)
			(end -0.120396 0.3048)
			(stroke
				(width 0.1)
				(type default)
			)
			(layer "B.Fab")
		)
		(pad "1" smd circle
			(at 0.40005 0 270)
			(size 0 0)
			(layers "B.Cu" "B.Mask" "B.Paste")
			(net "NC_PVCCD_HV_CPU0_ACSP8")
		)
		(pad "2" smd circle
			(at -0.40005 0 270)
			(size 0 0)
			(layers "B.Cu" "B.Mask" "B.Paste")
			(net "GND")
		)
	)
	(footprint ""
		(layer "B.Cu")
		(at 418.395404 -319.402968 180)
		(property "Reference" "R885"
			(at 0 0 0)
			(layer "B.SilkS")
			(hide yes)
			(effects
				(font
					(size 1.27 1.27)
				)
				(justify mirror)
			)
		)
		(property "Value" ""
			(at 0 0 0)
			(layer "B.Fab")
			(effects
				(font
					(size 1.27 1.27)
				)
				(justify mirror)
			)
		)
		(duplicate_pad_numbers_are_jumpers no)
		(fp_line
			(start 0.7874 0.4064)
			(end 0.7874 -0.4064)
			(stroke
				(width 0.1524)
				(type default)
			)
			(layer "B.SilkS")
		)
		(fp_line
			(start 0.7874 -0.4064)
			(end -0.7874 -0.4064)
			(stroke
				(width 0.1524)
				(type default)
			)
			(layer "B.SilkS")
		)
		(fp_line
			(start -0.7874 0.4064)
			(end 0.7874 0.4064)
			(stroke
				(width 0.1524)
				(type default)
			)
			(layer "B.SilkS")
		)
		(fp_line
			(start -0.7874 -0.4064)
			(end -0.7874 0.4064)
			(stroke
				(width 0.1524)
				(type default)
			)
			(layer "B.SilkS")
		)
		(fp_line
			(start 0.67945 0.3048)
			(end 0.67945 -0.305054)
			(stroke
				(width 0.1)
				(type default)
			)
			(layer "B.Fab")
		)
		(fp_line
			(start 0.67945 -0.305054)
			(end 0.12065 -0.305054)
			(stroke
				(width 0.1)
				(type default)
			)
			(layer "B.Fab")
		)
		(fp_line
			(start 0.12065 0.3048)
			(end 0.67945 0.3048)
			(stroke
				(width 0.1)
				(type default)
			)
			(layer "B.Fab")
		)
		(fp_line
			(start 0.12065 0.2794)
			(end 0.12065 0.3048)
			(stroke
				(width 0.1)
				(type default)
			)
			(layer "B.Fab")
		)
		(fp_line
			(start 0.12065 -0.2794)
			(end -0.12065 -0.2794)
			(stroke
				(width 0.1)
				(type default)
			)
			(layer "B.Fab")
		)
		(fp_line
			(start 0.12065 -0.305054)
			(end 0.12065 -0.2794)
			(stroke
				(width 0.1)
				(type default)
			)
			(layer "B.Fab")
		)
		(fp_line
			(start -0.120396 0.3048)
			(end -0.120396 0.2794)
			(stroke
				(width 0.1)
				(type default)
			)
			(layer "B.Fab")
		)
		(fp_line
			(start -0.120396 0.2794)
			(end 0.12065 0.2794)
			(stroke
				(width 0.1)
				(type default)
			)
			(layer "B.Fab")
		)
		(fp_line
			(start -0.12065 -0.2794)
			(end -0.12065 -0.3048)
			(stroke
				(width 0.1)
				(type default)
			)
			(layer "B.Fab")
		)
		(fp_line
			(start -0.12065 -0.3048)
			(end -0.67945 -0.3048)
			(stroke
				(width 0.1)
				(type default)
			)
			(layer "B.Fab")
		)
		(fp_line
			(start -0.67945 0.3048)
			(end -0.120396 0.3048)
			(stroke
				(width 0.1)
				(type default)
			)
			(layer "B.Fab")
		)
		(fp_line
			(start -0.67945 -0.3048)
			(end -0.67945 0.3048)
			(stroke
				(width 0.1)
				(type default)
			)
			(layer "B.Fab")
		)
		(pad "1" smd circle
			(at 0.40005 0)
			(size 0 0)
			(layers "B.Cu" "B.Mask" "B.Paste")
			(net "PWRGD_CHE_CPU0_DIMM1")
		)
		(pad "2" smd circle
			(at -0.40005 0)
			(size 0 0)
			(layers "B.Cu" "B.Mask" "B.Paste")
			(net "PWRGD_FAIL_CPU0_EF")
		)
	)
	(footprint ""
		(layer "B.Cu")
		(at 166.386002 -250.271534 180)
		(property "Reference" "R1236"
			(at 0 0 0)
			(layer "B.SilkS")
			(hide yes)
			(effects
				(font
					(size 1.27 1.27)
				)
				(justify mirror)
			)
		)
		(property "Value" ""
			(at 0 0 0)
			(layer "B.Fab")
			(effects
				(font
					(size 1.27 1.27)
				)
				(justify mirror)
			)
		)
		(duplicate_pad_numbers_are_jumpers no)
		(fp_line
			(start 0.7874 0.4064)
			(end 0.7874 -0.4064)
			(stroke
				(width 0.1524)
				(type default)
			)
			(layer "B.SilkS")
		)
		(fp_line
			(start 0.7874 -0.4064)
			(end -0.7874 -0.4064)
			(stroke
				(width 0.1524)
				(type default)
			)
			(layer "B.SilkS")
		)
		(fp_line
			(start -0.7874 0.4064)
			(end 0.7874 0.4064)
			(stroke
				(width 0.1524)
				(type default)
			)
			(layer "B.SilkS")
		)
		(fp_line
			(start -0.7874 -0.4064)
			(end -0.7874 0.4064)
			(stroke
				(width 0.1524)
				(type default)
			)
			(layer "B.SilkS")
		)
		(fp_line
			(start 0.67945 0.3048)
			(end 0.67945 -0.305054)
			(stroke
				(width 0.1)
				(type default)
			)
			(layer "B.Fab")
		)
		(fp_line
			(start 0.67945 -0.305054)
			(end 0.12065 -0.305054)
			(stroke
				(width 0.1)
				(type default)
			)
			(layer "B.Fab")
		)
		(fp_line
			(start 0.12065 0.3048)
			(end 0.67945 0.3048)
			(stroke
				(width 0.1)
				(type default)
			)
			(layer "B.Fab")
		)
		(fp_line
			(start 0.12065 0.2794)
			(end 0.12065 0.3048)
			(stroke
				(width 0.1)
				(type default)
			)
			(layer "B.Fab")
		)
		(fp_line
			(start 0.12065 -0.2794)
			(end -0.12065 -0.2794)
			(stroke
				(width 0.1)
				(type default)
			)
			(layer "B.Fab")
		)
		(fp_line
			(start 0.12065 -0.305054)
			(end 0.12065 -0.2794)
			(stroke
				(width 0.1)
				(type default)
			)
			(layer "B.Fab")
		)
		(fp_line
			(start -0.120396 0.3048)
			(end -0.120396 0.2794)
			(stroke
				(width 0.1)
				(type default)
			)
			(layer "B.Fab")
		)
		(fp_line
			(start -0.120396 0.2794)
			(end 0.12065 0.2794)
			(stroke
				(width 0.1)
				(type default)
			)
			(layer "B.Fab")
		)
		(fp_line
			(start -0.12065 -0.2794)
			(end -0.12065 -0.3048)
			(stroke
				(width 0.1)
				(type default)
			)
			(layer "B.Fab")
		)
		(fp_line
			(start -0.12065 -0.3048)
			(end -0.67945 -0.3048)
			(stroke
				(width 0.1)
				(type default)
			)
			(layer "B.Fab")
		)
		(fp_line
			(start -0.67945 0.3048)
			(end -0.120396 0.3048)
			(stroke
				(width 0.1)
				(type default)
			)
			(layer "B.Fab")
		)
		(fp_line
			(start -0.67945 -0.3048)
			(end -0.67945 0.3048)
			(stroke
				(width 0.1)
				(type default)
			)
			(layer "B.Fab")
		)
		(pad "1" smd circle
			(at 0.40005 0)
			(size 0 0)
			(layers "B.Cu" "B.Mask" "B.Paste")
			(net "GND")
		)
		(pad "2" smd circle
			(at -0.40005 0)
			(size 0 0)
			(layers "B.Cu" "B.Mask" "B.Paste")
			(net "PUD_XTAL_CPU1_MODE1")
		)
	)
)
